# T6G (Grand Teton) — schematic netlist excerpt (pin names and nets, part order shuffled) for the footprints in the layout excerpt that follows; sources: Cadence DE-HDL packaged netlist, KiCad conversion of 04192023_DAF0TMB3IC0_F0TG_MB_C_brd_V02_OCP.brd

R8082  Q_RES  10K 1% EMPTY  pkg 0402LF  page 86 : A = P3V3_AUX ; B = PWRGD_CHAF_CPU0_R1
PC6613_1  Q_CAP  3300PF 50V 10% X7R  pkg 0402  page 365 : A = SW_P12V_AUX_P0V9_RETIMER_CPU1_FLT ; B = GND

(kicad_pcb
	(version 20260206)
	(generator "pcbnew")
	(generator_version "10.0")
	(general
		(thickness 1.6)
		(legacy_teardrops no)
	)
	(paper "A4")
	(title_block
		(title "04192023_DAF0TMB3IC0_F0TG_MB_C_brd_V02_OCP.brd")
		(comment 1 "Grand Teton / footprints 3297-3298 of 8354")
	)
	(layers
		(0 "F.Cu" signal "TOP")
		(4 "In1.Cu" signal "GND")
		(6 "In2.Cu" signal "IN1")
		(8 "In3.Cu" signal "GND1")
		(10 "In4.Cu" signal "IN2")
		(12 "In5.Cu" signal "GND2")
		(14 "In6.Cu" signal "IN3")
		(16 "In7.Cu" signal "GND3")
		(18 "In8.Cu" signal "VCC")
		(20 "In9.Cu" signal "VCC1")
		(22 "In10.Cu" signal "GND4")
		(24 "In11.Cu" signal "IN4")
		(26 "In12.Cu" signal "GND5")
		(28 "In13.Cu" signal "IN5")
		(30 "In14.Cu" signal "GND6")
		(32 "In15.Cu" signal "IN6")
		(34 "In16.Cu" signal "GND7")
		(2 "B.Cu" signal "BOTTOM")
		(9 "F.Adhes" user "F.Adhesive")
		(11 "B.Adhes" user "B.Adhesive")
		(13 "F.Paste" user "Package Geometry/Pastemask Top")
		(15 "B.Paste" user "Package Geometry/Pastemask Bottom")
		(5 "F.SilkS" user "Ref Des/Silkscreen Top")
		(7 "B.SilkS" user "Ref Des/Silkscreen Bottom")
		(1 "F.Mask" user "Board Geometry/Soldermask Top")
		(3 "B.Mask" user "Board Geometry/Soldermask Bottom")
		(17 "Dwgs.User" user "User.Drawings")
		(19 "Cmts.User" user "User.Comments")
		(21 "Eco1.User" user "User.Eco1")
		(23 "Eco2.User" user "User.Eco2")
		(25 "Edge.Cuts" user "Board Geometry/Outline")
		(27 "Margin" user)
		(31 "F.CrtYd" user "Package Geometry/Place Bound Top")
		(29 "B.CrtYd" user "Package Geometry/Place Bound Bottom")
		(35 "F.Fab" user "Ref Des/Assembly Top")
		(33 "B.Fab" user "Ref Des/Assembly Bottom")
	)
	(footprint ""
		(layer "F.Cu")
		(at 20.369784 -393.539726)
		(property "Reference" "PC6613_1"
			(at 0 0 0)
			(layer "F.SilkS")
			(hide yes)
			(effects
				(font
					(size 1.27 1.27)
				)
			)
		)
		(property "Value" ""
			(at 0 0 0)
			(layer "F.Fab")
			(effects
				(font
					(size 1.27 1.27)
				)
			)
		)
		(duplicate_pad_numbers_are_jumpers no)
		(fp_line
			(start -0.7874 -0.4064)
			(end 0.7874 -0.4064)
			(stroke
				(width 0.1524)
				(type default)
			)
			(layer "F.SilkS")
		)
		(fp_line
			(start -0.7874 0.4064)
			(end -0.7874 -0.4064)
			(stroke
				(width 0.1524)
				(type default)
			)
			(layer "F.SilkS")
		)
		(fp_line
			(start 0.7874 -0.4064)
			(end 0.7874 0.4064)
			(stroke
				(width 0.1524)
				(type default)
			)
			(layer "F.SilkS")
		)
		(fp_line
			(start 0.7874 0.4064)
			(end -0.7874 0.4064)
			(stroke
				(width 0.1524)
				(type default)
			)
			(layer "F.SilkS")
		)
		(fp_line
			(start -0.67945 -0.305054)
			(end -0.12065 -0.305054)
			(stroke
				(width 0.1)
				(type default)
			)
			(layer "F.Fab")
		)
		(fp_line
			(start -0.67945 0.3048)
			(end -0.67945 -0.305054)
			(stroke
				(width 0.1)
				(type default)
			)
			(layer "F.Fab")
		)
		(fp_line
			(start -0.12065 -0.305054)
			(end -0.12065 -0.2794)
			(stroke
				(width 0.1)
				(type default)
			)
			(layer "F.Fab")
		)
		(fp_line
			(start -0.12065 -0.2794)
			(end 0.12065 -0.2794)
			(stroke
				(width 0.1)
				(type default)
			)
			(layer "F.Fab")
		)
		(fp_line
			(start -0.12065 0.2794)
			(end -0.12065 0.3048)
			(stroke
				(width 0.1)
				(type default)
			)
			(layer "F.Fab")
		)
		(fp_line
			(start -0.12065 0.3048)
			(end -0.67945 0.3048)
			(stroke
				(width 0.1)
				(type default)
			)
			(layer "F.Fab")
		)
		(fp_line
			(start 0.120396 0.2794)
			(end -0.12065 0.2794)
			(stroke
				(width 0.1)
				(type default)
			)
			(layer "F.Fab")
		)
		(fp_line
			(start 0.120396 0.3048)
			(end 0.120396 0.2794)
			(stroke
				(width 0.1)
				(type default)
			)
			(layer "F.Fab")
		)
		(fp_line
			(start 0.12065 -0.3048)
			(end 0.67945 -0.3048)
			(stroke
				(width 0.1)
				(type default)
			)
			(layer "F.Fab")
		)
		(fp_line
			(start 0.12065 -0.2794)
			(end 0.12065 -0.3048)
			(stroke
				(width 0.1)
				(type default)
			)
			(layer "F.Fab")
		)
		(fp_line
			(start 0.67945 -0.3048)
			(end 0.67945 0.3048)
			(stroke
				(width 0.1)
				(type default)
			)
			(layer "F.Fab")
		)
		(fp_line
			(start 0.67945 0.3048)
			(end 0.120396 0.3048)
			(stroke
				(width 0.1)
				(type default)
			)
			(layer "F.Fab")
		)
		(pad "1" smd circle
			(at -0.40005 0)
			(size 0 0)
			(layers "F.Cu" "F.Mask" "F.Paste")
			(net "SW_P12V_AUX_P0V9_RETIMER_CPU1_FLT")
		)
		(pad "2" smd circle
			(at 0.40005 0)
			(size 0 0)
			(layers "F.Cu" "F.Mask" "F.Paste")
			(net "GND")
		)
	)
	(footprint ""
		(layer "F.Cu")
		(at 200.914 -103.505)
		(property "Reference" "R8082"
			(at 0 0 0)
			(layer "F.SilkS")
			(hide yes)
			(effects
				(font
					(size 1.27 1.27)
				)
			)
		)
		(property "Value" ""
			(at 0 0 0)
			(layer "F.Fab")
			(effects
				(font
					(size 1.27 1.27)
				)
			)
		)
		(duplicate_pad_numbers_are_jumpers no)
		(fp_line
			(start -0.7874 -0.4064)
			(end 0.7874 -0.4064)
			(stroke
				(width 0.1524)
				(type default)
			)
			(layer "F.SilkS")
		)
		(fp_line
			(start -0.7874 0.4064)
			(end -0.7874 -0.4064)
			(stroke
				(width 0.1524)
				(type default)
			)
			(layer "F.SilkS")
		)
		(fp_line
			(start 0.7874 -0.4064)
			(end 0.7874 0.4064)
			(stroke
				(width 0.1524)
				(type default)
			)
			(layer "F.SilkS")
		)
		(fp_line
			(start 0.7874 0.4064)
			(end -0.7874 0.4064)
			(stroke
				(width 0.1524)
				(type default)
			)
			(layer "F.SilkS")
		)
		(fp_line
			(start -0.67945 -0.305054)
			(end -0.12065 -0.305054)
			(stroke
				(width 0.1)
				(type default)
			)
			(layer "F.Fab")
		)
		(fp_line
			(start -0.67945 0.3048)
			(end -0.67945 -0.305054)
			(stroke
				(width 0.1)
				(type default)
			)
			(layer "F.Fab")
		)
		(fp_line
			(start -0.12065 -0.305054)
			(end -0.12065 -0.2794)
			(stroke
				(width 0.1)
				(type default)
			)
			(layer "F.Fab")
		)
		(fp_line
			(start -0.12065 -0.2794)
			(end 0.12065 -0.2794)
			(stroke
				(width 0.1)
				(type default)
			)
			(layer "F.Fab")
		)
		(fp_line
			(start -0.12065 0.2794)
			(end -0.12065 0.3048)
			(stroke
				(width 0.1)
				(type default)
			)
			(layer "F.Fab")
		)
		(fp_line
			(start -0.12065 0.3048)
			(end -0.67945 0.3048)
			(stroke
				(width 0.1)
				(type default)
			)
			(layer "F.Fab")
		)
		(fp_line
			(start 0.120396 0.2794)
			(end -0.12065 0.2794)
			(stroke
				(width 0.1)
				(type default)
			)
			(layer "F.Fab")
		)
		(fp_line
			(start 0.120396 0.3048)
			(end 0.120396 0.2794)
			(stroke
				(width 0.1)
				(type default)
			)
			(layer "F.Fab")
		)
		(fp_line
			(start 0.12065 -0.3048)
			(end 0.67945 -0.3048)
			(stroke
				(width 0.1)
				(type default)
			)
			(layer "F.Fab")
		)
		(fp_line
			(start 0.12065 -0.2794)
			(end 0.12065 -0.3048)
			(stroke
				(width 0.1)
				(type default)
			)
			(layer "F.Fab")
		)
		(fp_line
			(start 0.67945 -0.3048)
			(end 0.67945 0.3048)
			(stroke
				(width 0.1)
				(type default)
			)
			(layer "F.Fab")
		)
		(fp_line
			(start 0.67945 0.3048)
			(end 0.120396 0.3048)
			(stroke
				(width 0.1)
				(type default)
			)
			(layer "F.Fab")
		)
		(pad "1" smd circle
			(at -0.40005 0)
			(size 0 0)
			(layers "F.Cu" "F.Mask" "F.Paste")
			(net "P3V3_AUX")
		)
		(pad "2" smd circle
			(at 0.40005 0)
			(size 0 0)
			(layers "F.Cu" "F.Mask" "F.Paste")
			(net "PWRGD_CHAF_CPU0_R1")
		)
	)
)
